(kicad_pcb
	(version 20260206)
	(generator "pcbnew")
	(generator_version "10.0")
	(general
		(thickness 1.6)
		(legacy_teardrops no)
	)
	(paper "A4")
	(title_block
		(title "04192023_DAF0TMB3IC0_F0TG_MB_C_brd_V02_OCP.brd")
		(comment 1 "Grand Teton / footprints 6014-6019 of 8354")
	)
	(layers
		(0 "F.Cu" signal "TOP")
		(4 "In1.Cu" signal "GND")
		(6 "In2.Cu" signal "IN1")
		(8 "In3.Cu" signal "GND1")
		(10 "In4.Cu" signal "IN2")
		(12 "In5.Cu" signal "GND2")
		(14 "In6.Cu" signal "IN3")
		(16 "In7.Cu" signal "GND3")
		(18 "In8.Cu" signal "VCC")
		(20 "In9.Cu" signal "VCC1")
		(22 "In10.Cu" signal "GND4")
		(24 "In11.Cu" signal "IN4")
		(26 "In12.Cu" signal "GND5")
		(28 "In13.Cu" signal "IN5")
		(30 "In14.Cu" signal "GND6")
		(32 "In15.Cu" signal "IN6")
		(34 "In16.Cu" signal "GND7")
		(2 "B.Cu" signal "BOTTOM")
		(9 "F.Adhes" user "F.Adhesive")
		(11 "B.Adhes" user "B.Adhesive")
		(13 "F.Paste" user "Package Geometry/Pastemask Top")
		(15 "B.Paste" user "Package Geometry/Pastemask Bottom")
		(5 "F.SilkS" user "Ref Des/Silkscreen Top")
		(7 "B.SilkS" user "Ref Des/Silkscreen Bottom")
		(1 "F.Mask" user "Board Geometry/Soldermask Top")
		(3 "B.Mask" user "Board Geometry/Soldermask Bottom")
		(17 "Dwgs.User" user "User.Drawings")
		(19 "Cmts.User" user "User.Comments")
		(21 "Eco1.User" user "User.Eco1")
		(23 "Eco2.User" user "User.Eco2")
		(25 "Edge.Cuts" user "Board Geometry/Outline")
		(27 "Margin" user)
		(31 "F.CrtYd" user "Package Geometry/Place Bound Top")
		(29 "B.CrtYd" user "Package Geometry/Place Bound Bottom")
		(35 "F.Fab" user "Ref Des/Assembly Top")
		(33 "B.Fab" user "Ref Des/Assembly Bottom")
	)
	(footprint ""
		(layer "B.Cu")
		(at 228.383592 -290.564062)
		(property "Reference" "PR6520"
			(at 0 0 0)
			(layer "B.SilkS")
			(hide yes)
			(effects
				(font
					(size 1.27 1.27)
				)
				(justify mirror)
			)
		)
		(property "Value" ""
			(at 0 0 0)
			(layer "B.Fab")
			(effects
				(font
					(size 1.27 1.27)
				)
				(justify mirror)
			)
		)
		(duplicate_pad_numbers_are_jumpers no)
		(fp_line
			(start -0.7874 -0.4064)
			(end -0.7874 0.4064)
			(stroke
				(width 0.1524)
				(type default)
			)
			(layer "B.SilkS")
		)
		(fp_line
			(start -0.7874 0.4064)
			(end 0.7874 0.4064)
			(stroke
				(width 0.1524)
				(type default)
			)
			(layer "B.SilkS")
		)
		(fp_line
			(start 0.7874 -0.4064)
			(end -0.7874 -0.4064)
			(stroke
				(width 0.1524)
				(type default)
			)
			(layer "B.SilkS")
		)
		(fp_line
			(start 0.7874 0.4064)
			(end 0.7874 -0.4064)
			(stroke
				(width 0.1524)
				(type default)
			)
			(layer "B.SilkS")
		)
		(fp_line
			(start -0.67945 -0.3048)
			(end -0.67945 0.3048)
			(stroke
				(width 0.1)
				(type default)
			)
			(layer "B.Fab")
		)
		(fp_line
			(start -0.67945 0.3048)
			(end -0.120396 0.3048)
			(stroke
				(width 0.1)
				(type default)
			)
			(layer "B.Fab")
		)
		(fp_line
			(start -0.12065 -0.3048)
			(end -0.67945 -0.3048)
			(stroke
				(width 0.1)
				(type default)
			)
			(layer "B.Fab")
		)
		(fp_line
			(start -0.12065 -0.2794)
			(end -0.12065 -0.3048)
			(stroke
				(width 0.1)
				(type default)
			)
			(layer "B.Fab")
		)
		(fp_line
			(start -0.120396 0.2794)
			(end 0.12065 0.2794)
			(stroke
				(width 0.1)
				(type default)
			)
			(layer "B.Fab")
		)
		(fp_line
			(start -0.120396 0.3048)
			(end -0.120396 0.2794)
			(stroke
				(width 0.1)
				(type default)
			)
			(layer "B.Fab")
		)
		(fp_line
			(start 0.12065 -0.305054)
			(end 0.12065 -0.2794)
			(stroke
				(width 0.1)
				(type default)
			)
			(layer "B.Fab")
		)
		(fp_line
			(start 0.12065 -0.2794)
			(end -0.12065 -0.2794)
			(stroke
				(width 0.1)
				(type default)
			)
			(layer "B.Fab")
		)
		(fp_line
			(start 0.12065 0.2794)
			(end 0.12065 0.3048)
			(stroke
				(width 0.1)
				(type default)
			)
			(layer "B.Fab")
		)
		(fp_line
			(start 0.12065 0.3048)
			(end 0.67945 0.3048)
			(stroke
				(width 0.1)
				(type default)
			)
			(layer "B.Fab")
		)
		(fp_line
			(start 0.67945 -0.305054)
			(end 0.12065 -0.305054)
			(stroke
				(width 0.1)
				(type default)
			)
			(layer "B.Fab")
		)
		(fp_line
			(start 0.67945 0.3048)
			(end 0.67945 -0.305054)
			(stroke
				(width 0.1)
				(type default)
			)
			(layer "B.Fab")
		)
		(pad "1" smd circle
			(at 0.40005 0 180)
			(size 0 0)
			(layers "B.Cu" "B.Mask" "B.Paste")
			(net "GND")
		)
		(pad "2" smd circle
			(at -0.40005 0 180)
			(size 0 0)
			(layers "B.Cu" "B.Mask" "B.Paste")
			(net "P1V8_RETIMER_CPU1_MODE")
		)
	)
	(footprint ""
		(layer "B.Cu")
		(at 51.232562 -347.780356 -90)
		(property "Reference" "PR277"
			(at 0 0 90)
			(layer "B.SilkS")
			(hide yes)
			(effects
				(font
					(size 1.27 1.27)
				)
				(justify mirror)
			)
		)
		(property "Value" ""
			(at 0 0 90)
			(layer "B.Fab")
			(effects
				(font
					(size 1.27 1.27)
				)
				(justify mirror)
			)
		)
		(duplicate_pad_numbers_are_jumpers no)
		(fp_line
			(start -0.7874 0.4064)
			(end 0.7874 0.4064)
			(stroke
				(width 0.1524)
				(type default)
			)
			(layer "B.SilkS")
		)
		(fp_line
			(start 0.7874 0.4064)
			(end 0.7874 -0.4064)
			(stroke
				(width 0.1524)
				(type default)
			)
			(layer "B.SilkS")
		)
		(fp_line
			(start -0.7874 -0.4064)
			(end -0.7874 0.4064)
			(stroke
				(width 0.1524)
				(type default)
			)
			(layer "B.SilkS")
		)
		(fp_line
			(start 0.7874 -0.4064)
			(end -0.7874 -0.4064)
			(stroke
				(width 0.1524)
				(type default)
			)
			(layer "B.SilkS")
		)
		(fp_line
			(start -0.67945 0.3048)
			(end -0.120396 0.3048)
			(stroke
				(width 0.1)
				(type default)
			)
			(layer "B.Fab")
		)
		(fp_line
			(start -0.120396 0.3048)
			(end -0.120396 0.2794)
			(stroke
				(width 0.1)
				(type default)
			)
			(layer "B.Fab")
		)
		(fp_line
			(start 0.12065 0.3048)
			(end 0.67945 0.3048)
			(stroke
				(width 0.1)
				(type default)
			)
			(layer "B.Fab")
		)
		(fp_line
			(start 0.67945 0.3048)
			(end 0.67945 -0.305054)
			(stroke
				(width 0.1)
				(type default)
			)
			(layer "B.Fab")
		)
		(fp_line
			(start -0.120396 0.2794)
			(end 0.12065 0.2794)
			(stroke
				(width 0.1)
				(type default)
			)
			(layer "B.Fab")
		)
		(fp_line
			(start 0.12065 0.2794)
			(end 0.12065 0.3048)
			(stroke
				(width 0.1)
				(type default)
			)
			(layer "B.Fab")
		)
		(fp_line
			(start -0.12065 -0.2794)
			(end -0.12065 -0.3048)
			(stroke
				(width 0.1)
				(type default)
			)
			(layer "B.Fab")
		)
		(fp_line
			(start 0.12065 -0.2794)
			(end -0.12065 -0.2794)
			(stroke
				(width 0.1)
				(type default)
			)
			(layer "B.Fab")
		)
		(fp_line
			(start -0.67945 -0.3048)
			(end -0.67945 0.3048)
			(stroke
				(width 0.1)
				(type default)
			)
			(layer "B.Fab")
		)
		(fp_line
			(start -0.12065 -0.3048)
			(end -0.67945 -0.3048)
			(stroke
				(width 0.1)
				(type default)
			)
			(layer "B.Fab")
		)
		(fp_line
			(start 0.12065 -0.305054)
			(end 0.12065 -0.2794)
			(stroke
				(width 0.1)
				(type default)
			)
			(layer "B.Fab")
		)
		(fp_line
			(start 0.67945 -0.305054)
			(end 0.12065 -0.305054)
			(stroke
				(width 0.1)
				(type default)
			)
			(layer "B.Fab")
		)
		(pad "1" smd circle
			(at 0.40005 0 90)
			(size 0 0)
			(layers "B.Cu" "B.Mask" "B.Paste")
			(net "PVDDCR_CPU1_P1_PVCC")
		)
		(pad "2" smd circle
			(at -0.40005 0 90)
			(size 0 0)
			(layers "B.Cu" "B.Mask" "B.Paste")
			(net "PVDDIO_P1_VCC1")
		)
	)
	(footprint ""
		(layer "B.Cu")
		(at 181.37886 -406.918922 90)
		(property "Reference" "R1714"
			(at 0 0 90)
			(layer "B.SilkS")
			(hide yes)
			(effects
				(font
					(size 1.27 1.27)
				)
				(justify mirror)
			)
		)
		(property "Value" ""
			(at 0 0 90)
			(layer "B.Fab")
			(effects
				(font
					(size 1.27 1.27)
				)
				(justify mirror)
			)
		)
		(duplicate_pad_numbers_are_jumpers no)
		(fp_line
			(start 0.7874 -0.4064)
			(end -0.7874 -0.4064)
			(stroke
				(width 0.1524)
				(type default)
			)
			(layer "B.SilkS")
		)
		(fp_line
			(start -0.7874 -0.4064)
			(end -0.7874 0.4064)
			(stroke
				(width 0.1524)
				(type default)
			)
			(layer "B.SilkS")
		)
		(fp_line
			(start 0.7874 0.4064)
			(end 0.7874 -0.4064)
			(stroke
				(width 0.1524)
				(type default)
			)
			(layer "B.SilkS")
		)
		(fp_line
			(start -0.7874 0.4064)
			(end 0.7874 0.4064)
			(stroke
				(width 0.1524)
				(type default)
			)
			(layer "B.SilkS")
		)
		(fp_line
			(start 0.67945 -0.305054)
			(end 0.12065 -0.305054)
			(stroke
				(width 0.1)
				(type default)
			)
			(layer "B.Fab")
		)
		(fp_line
			(start 0.12065 -0.305054)
			(end 0.12065 -0.2794)
			(stroke
				(width 0.1)
				(type default)
			)
			(layer "B.Fab")
		)
		(fp_line
			(start -0.12065 -0.3048)
			(end -0.67945 -0.3048)
			(stroke
				(width 0.1)
				(type default)
			)
			(layer "B.Fab")
		)
		(fp_line
			(start -0.67945 -0.3048)
			(end -0.67945 0.3048)
			(stroke
				(width 0.1)
				(type default)
			)
			(layer "B.Fab")
		)
		(fp_line
			(start 0.12065 -0.2794)
			(end -0.12065 -0.2794)
			(stroke
				(width 0.1)
				(type default)
			)
			(layer "B.Fab")
		)
		(fp_line
			(start -0.12065 -0.2794)
			(end -0.12065 -0.3048)
			(stroke
				(width 0.1)
				(type default)
			)
			(layer "B.Fab")
		)
		(fp_line
			(start 0.12065 0.2794)
			(end 0.12065 0.3048)
			(stroke
				(width 0.1)
				(type default)
			)
			(layer "B.Fab")
		)
		(fp_line
			(start -0.120396 0.2794)
			(end 0.12065 0.2794)
			(stroke
				(width 0.1)
				(type default)
			)
			(layer "B.Fab")
		)
		(fp_line
			(start 0.67945 0.3048)
			(end 0.67945 -0.305054)
			(stroke
				(width 0.1)
				(type default)
			)
			(layer "B.Fab")
		)
		(fp_line
			(start 0.12065 0.3048)
			(end 0.67945 0.3048)
			(stroke
				(width 0.1)
				(type default)
			)
			(layer "B.Fab")
		)
		(fp_line
			(start -0.120396 0.3048)
			(end -0.120396 0.2794)
			(stroke
				(width 0.1)
				(type default)
			)
			(layer "B.Fab")
		)
		(fp_line
			(start -0.67945 0.3048)
			(end -0.120396 0.3048)
			(stroke
				(width 0.1)
				(type default)
			)
			(layer "B.Fab")
		)
		(pad "1" smd circle
			(at 0.40005 0 270)
			(size 0 0)
			(layers "B.Cu" "B.Mask" "B.Paste")
			(net "SMB_SML1_PMBUS_HSC_SDA")
		)
		(pad "2" smd circle
			(at -0.40005 0 270)
			(size 0 0)
			(layers "B.Cu" "B.Mask" "B.Paste")
			(net "SMB_SML1_PMBUS_HSC_R_SDA")
		)
	)
	(footprint ""
		(layer "B.Cu")
		(at 182.225188 -418.423598 -90)
		(property "Reference" "R2800"
			(at 0 0 90)
			(layer "B.SilkS")
			(hide yes)
			(effects
				(font
					(size 1.27 1.27)
				)
				(justify mirror)
			)
		)
		(property "Value" ""
			(at 0 0 90)
			(layer "B.Fab")
			(effects
				(font
					(size 1.27 1.27)
				)
				(justify mirror)
			)
		)
		(duplicate_pad_numbers_are_jumpers no)
		(fp_line
			(start -0.7874 0.4064)
			(end 0.7874 0.4064)
			(stroke
				(width 0.1524)
				(type default)
			)
			(layer "B.SilkS")
		)
		(fp_line
			(start 0.7874 0.4064)
			(end 0.7874 -0.4064)
			(stroke
				(width 0.1524)
				(type default)
			)
			(layer "B.SilkS")
		)
		(fp_line
			(start -0.7874 -0.4064)
			(end -0.7874 0.4064)
			(stroke
				(width 0.1524)
				(type default)
			)
			(layer "B.SilkS")
		)
		(fp_line
			(start 0.7874 -0.4064)
			(end -0.7874 -0.4064)
			(stroke
				(width 0.1524)
				(type default)
			)
			(layer "B.SilkS")
		)
		(fp_line
			(start -0.67945 0.3048)
			(end -0.120396 0.3048)
			(stroke
				(width 0.1)
				(type default)
			)
			(layer "B.Fab")
		)
		(fp_line
			(start -0.120396 0.3048)
			(end -0.120396 0.2794)
			(stroke
				(width 0.1)
				(type default)
			)
			(layer "B.Fab")
		)
		(fp_line
			(start 0.12065 0.3048)
			(end 0.67945 0.3048)
			(stroke
				(width 0.1)
				(type default)
			)
			(layer "B.Fab")
		)
		(fp_line
			(start 0.67945 0.3048)
			(end 0.67945 -0.305054)
			(stroke
				(width 0.1)
				(type default)
			)
			(layer "B.Fab")
		)
		(fp_line
			(start -0.120396 0.2794)
			(end 0.12065 0.2794)
			(stroke
				(width 0.1)
				(type default)
			)
			(layer "B.Fab")
		)
		(fp_line
			(start 0.12065 0.2794)
			(end 0.12065 0.3048)
			(stroke
				(width 0.1)
				(type default)
			)
			(layer "B.Fab")
		)
		(fp_line
			(start -0.12065 -0.2794)
			(end -0.12065 -0.3048)
			(stroke
				(width 0.1)
				(type default)
			)
			(layer "B.Fab")
		)
		(fp_line
			(start 0.12065 -0.2794)
			(end -0.12065 -0.2794)
			(stroke
				(width 0.1)
				(type default)
			)
			(layer "B.Fab")
		)
		(fp_line
			(start -0.67945 -0.3048)
			(end -0.67945 0.3048)
			(stroke
				(width 0.1)
				(type default)
			)
			(layer "B.Fab")
		)
		(fp_line
			(start -0.12065 -0.3048)
			(end -0.67945 -0.3048)
			(stroke
				(width 0.1)
				(type default)
			)
			(layer "B.Fab")
		)
		(fp_line
			(start 0.12065 -0.305054)
			(end 0.12065 -0.2794)
			(stroke
				(width 0.1)
				(type default)
			)
			(layer "B.Fab")
		)
		(fp_line
			(start 0.67945 -0.305054)
			(end 0.12065 -0.305054)
			(stroke
				(width 0.1)
				(type default)
			)
			(layer "B.Fab")
		)
		(pad "1" smd circle
			(at 0.40005 0 90)
			(size 0 0)
			(layers "B.Cu" "B.Mask" "B.Paste")
			(net "SMB_FAN_3V3AUX_R_SCL")
		)
		(pad "2" smd circle
			(at -0.40005 0 90)
			(size 0 0)
			(layers "B.Cu" "B.Mask" "B.Paste")
			(net "SMB_FAN_3V3AUX_BUF_SCL")
		)
	)
	(footprint ""
		(layer "B.Cu")
		(at 83.646264 -388.011162 -90)
		(property "Reference" "C334"
			(at 0 0 90)
			(layer "B.SilkS")
			(hide yes)
			(effects
				(font
					(size 1.27 1.27)
				)
				(justify mirror)
			)
		)
		(property "Value" ""
			(at 0 0 90)
			(layer "B.Fab")
			(effects
				(font
					(size 1.27 1.27)
				)
				(justify mirror)
			)
		)
		(duplicate_pad_numbers_are_jumpers no)
		(fp_line
			(start -0.299974 0.150114)
			(end 0.299974 0.150114)
			(stroke
				(width 0.1)
				(type default)
			)
			(layer "B.Fab")
		)
		(fp_line
			(start 0.299974 0.150114)
			(end 0.299974 -0.150114)
			(stroke
				(width 0.1)
				(type default)
			)
			(layer "B.Fab")
		)
		(fp_line
			(start -0.299974 -0.150114)
			(end -0.299974 0.150114)
			(stroke
				(width 0.1)
				(type default)
			)
			(layer "B.Fab")
		)
		(fp_line
			(start 0.299974 -0.150114)
			(end -0.299974 -0.150114)
			(stroke
				(width 0.1)
				(type default)
			)
			(layer "B.Fab")
		)
		(pad "1" smd rect
			(at 0.2667 0 90)
			(size 0.3048 0.381)
			(layers "B.Cu" "B.Mask" "B.Paste")
			(net "P0V9_CPU1_RT1_2A")
		)
		(pad "2" smd rect
			(at -0.2667 0 90)
			(size 0.3048 0.381)
			(layers "B.Cu" "B.Mask" "B.Paste")
			(net "GND")
		)
	)
	(footprint ""
		(layer "B.Cu")
		(at 438.766966 -425.184824 -90)
		(property "Reference" "PR6615"
			(at 0 0 90)
			(layer "B.SilkS")
			(hide yes)
			(effects
				(font
					(size 1.27 1.27)
				)
				(justify mirror)
			)
		)
		(property "Value" ""
			(at 0 0 90)
			(layer "B.Fab")
			(effects
				(font
					(size 1.27 1.27)
				)
				(justify mirror)
			)
		)
		(duplicate_pad_numbers_are_jumpers no)
		(fp_line
			(start -0.7874 0.4064)
			(end 0.7874 0.4064)
			(stroke
				(width 0.1524)
				(type default)
			)
			(layer "B.SilkS")
		)
		(fp_line
			(start 0.7874 0.4064)
			(end 0.7874 -0.4064)
			(stroke
				(width 0.1524)
				(type default)
			)
			(layer "B.SilkS")
		)
		(fp_line
			(start -0.7874 -0.4064)
			(end -0.7874 0.4064)
			(stroke
				(width 0.1524)
				(type default)
			)
			(layer "B.SilkS")
		)
		(fp_line
			(start 0.7874 -0.4064)
			(end -0.7874 -0.4064)
			(stroke
				(width 0.1524)
				(type default)
			)
			(layer "B.SilkS")
		)
		(fp_line
			(start -0.67945 0.3048)
			(end -0.120396 0.3048)
			(stroke
				(width 0.1)
				(type default)
			)
			(layer "B.Fab")
		)
		(fp_line
			(start -0.120396 0.3048)
			(end -0.120396 0.2794)
			(stroke
				(width 0.1)
				(type default)
			)
			(layer "B.Fab")
		)
		(fp_line
			(start 0.12065 0.3048)
			(end 0.67945 0.3048)
			(stroke
				(width 0.1)
				(type default)
			)
			(layer "B.Fab")
		)
		(fp_line
			(start 0.67945 0.3048)
			(end 0.67945 -0.305054)
			(stroke
				(width 0.1)
				(type default)
			)
			(layer "B.Fab")
		)
		(fp_line
			(start -0.120396 0.2794)
			(end 0.12065 0.2794)
			(stroke
				(width 0.1)
				(type default)
			)
			(layer "B.Fab")
		)
		(fp_line
			(start 0.12065 0.2794)
			(end 0.12065 0.3048)
			(stroke
				(width 0.1)
				(type default)
			)
			(layer "B.Fab")
		)
		(fp_line
			(start -0.12065 -0.2794)
			(end -0.12065 -0.3048)
			(stroke
				(width 0.1)
				(type default)
			)
			(layer "B.Fab")
		)
		(fp_line
			(start 0.12065 -0.2794)
			(end -0.12065 -0.2794)
			(stroke
				(width 0.1)
				(type default)
			)
			(layer "B.Fab")
		)
		(fp_line
			(start -0.67945 -0.3048)
			(end -0.67945 0.3048)
			(stroke
				(width 0.1)
				(type default)
			)
			(layer "B.Fab")
		)
		(fp_line
			(start -0.12065 -0.3048)
			(end -0.67945 -0.3048)
			(stroke
				(width 0.1)
				(type default)
			)
			(layer "B.Fab")
		)
		(fp_line
			(start 0.12065 -0.305054)
			(end 0.12065 -0.2794)
			(stroke
				(width 0.1)
				(type default)
			)
			(layer "B.Fab")
		)
		(fp_line
			(start 0.67945 -0.305054)
			(end 0.12065 -0.305054)
			(stroke
				(width 0.1)
				(type default)
			)
			(layer "B.Fab")
		)
		(pad "1" smd circle
			(at 0.40005 0 90)
			(size 0 0)
			(layers "B.Cu" "B.Mask" "B.Paste")
			(net "P3V3_AUX")
		)
		(pad "2" smd circle
			(at -0.40005 0 90)
			(size 0 0)
			(layers "B.Cu" "B.Mask" "B.Paste")
			(net "TP_P0V9_RETIMER_CPU0_VRHOT")
		)
	)
)
